(kicad_pcb
	(version 20260206)
	(generator "pcbnew")
	(generator_version "10.0")
	(general
		(thickness 1.6)
		(legacy_teardrops no)
	)
	(paper "A4")
	(title_block
		(title "03242023_DA0F0TMBIJ0_F0T_Motherboard_J_brd_V01_OCP.brd")
		(comment 1 "Grand Teton / footprints 66-72 of 6105")
	)
	(layers
		(0 "F.Cu" signal "TOP")
		(4 "In1.Cu" signal "GND")
		(6 "In2.Cu" signal "IN1")
		(8 "In3.Cu" signal "GND1")
		(10 "In4.Cu" signal "IN2")
		(12 "In5.Cu" signal "GND2")
		(14 "In6.Cu" signal "IN3")
		(16 "In7.Cu" signal "GND3")
		(18 "In8.Cu" signal "VCC")
		(20 "In9.Cu" signal "VCC1")
		(22 "In10.Cu" signal "GND4")
		(24 "In11.Cu" signal "IN4")
		(26 "In12.Cu" signal "GND5")
		(28 "In13.Cu" signal "IN5")
		(30 "In14.Cu" signal "GND6")
		(32 "In15.Cu" signal "IN6")
		(34 "In16.Cu" signal "GND7")
		(2 "B.Cu" signal "BOTTOM")
		(9 "F.Adhes" user "F.Adhesive")
		(11 "B.Adhes" user "B.Adhesive")
		(13 "F.Paste" user "Package Geometry/Pastemask Top")
		(15 "B.Paste" user "Package Geometry/Pastemask Bottom")
		(5 "F.SilkS" user "Ref Des/Silkscreen Top")
		(7 "B.SilkS" user "Ref Des/Silkscreen Bottom")
		(1 "F.Mask" user "Board Geometry/Soldermask Top")
		(3 "B.Mask" user "Board Geometry/Soldermask Bottom")
		(17 "Dwgs.User" user "User.Drawings")
		(19 "Cmts.User" user "User.Comments")
		(21 "Eco1.User" user "User.Eco1")
		(23 "Eco2.User" user "User.Eco2")
		(25 "Edge.Cuts" user "Board Geometry/Outline")
		(27 "Margin" user)
		(31 "F.CrtYd" user "Package Geometry/Place Bound Top")
		(29 "B.CrtYd" user "Package Geometry/Place Bound Bottom")
		(35 "F.Fab" user "Ref Des/Assembly Top")
		(33 "B.Fab" user "Ref Des/Assembly Bottom")
	)
	(footprint ""
		(layer "F.Cu")
		(at 306.090574 -426.179742)
		(property "Reference" "R4264"
			(at 0 0 0)
			(layer "F.SilkS")
			(hide yes)
			(effects
				(font
					(size 1.27 1.27)
				)
			)
		)
		(property "Value" ""
			(at 0 0 0)
			(layer "F.Fab")
			(effects
				(font
					(size 1.27 1.27)
				)
			)
		)
		(duplicate_pad_numbers_are_jumpers no)
		(fp_line
			(start -0.7874 -0.4064)
			(end 0.7874 -0.4064)
			(stroke
				(width 0.1524)
				(type default)
			)
			(layer "F.SilkS")
		)
		(fp_line
			(start -0.7874 0.4064)
			(end -0.7874 -0.4064)
			(stroke
				(width 0.1524)
				(type default)
			)
			(layer "F.SilkS")
		)
		(fp_line
			(start 0.7874 -0.4064)
			(end 0.7874 0.4064)
			(stroke
				(width 0.1524)
				(type default)
			)
			(layer "F.SilkS")
		)
		(fp_line
			(start 0.7874 0.4064)
			(end -0.7874 0.4064)
			(stroke
				(width 0.1524)
				(type default)
			)
			(layer "F.SilkS")
		)
		(fp_line
			(start -0.67945 -0.305054)
			(end -0.12065 -0.305054)
			(stroke
				(width 0.1)
				(type default)
			)
			(layer "F.Fab")
		)
		(fp_line
			(start -0.67945 0.3048)
			(end -0.67945 -0.305054)
			(stroke
				(width 0.1)
				(type default)
			)
			(layer "F.Fab")
		)
		(fp_line
			(start -0.12065 -0.305054)
			(end -0.12065 -0.2794)
			(stroke
				(width 0.1)
				(type default)
			)
			(layer "F.Fab")
		)
		(fp_line
			(start -0.12065 -0.2794)
			(end 0.12065 -0.2794)
			(stroke
				(width 0.1)
				(type default)
			)
			(layer "F.Fab")
		)
		(fp_line
			(start -0.12065 0.2794)
			(end -0.12065 0.3048)
			(stroke
				(width 0.1)
				(type default)
			)
			(layer "F.Fab")
		)
		(fp_line
			(start -0.12065 0.3048)
			(end -0.67945 0.3048)
			(stroke
				(width 0.1)
				(type default)
			)
			(layer "F.Fab")
		)
		(fp_line
			(start 0.120396 0.2794)
			(end -0.12065 0.2794)
			(stroke
				(width 0.1)
				(type default)
			)
			(layer "F.Fab")
		)
		(fp_line
			(start 0.120396 0.3048)
			(end 0.120396 0.2794)
			(stroke
				(width 0.1)
				(type default)
			)
			(layer "F.Fab")
		)
		(fp_line
			(start 0.12065 -0.3048)
			(end 0.67945 -0.3048)
			(stroke
				(width 0.1)
				(type default)
			)
			(layer "F.Fab")
		)
		(fp_line
			(start 0.12065 -0.2794)
			(end 0.12065 -0.3048)
			(stroke
				(width 0.1)
				(type default)
			)
			(layer "F.Fab")
		)
		(fp_line
			(start 0.67945 -0.3048)
			(end 0.67945 0.3048)
			(stroke
				(width 0.1)
				(type default)
			)
			(layer "F.Fab")
		)
		(fp_line
			(start 0.67945 0.3048)
			(end 0.120396 0.3048)
			(stroke
				(width 0.1)
				(type default)
			)
			(layer "F.Fab")
		)
		(pad "1" smd circle
			(at -0.40005 0)
			(size 0 0)
			(layers "F.Cu" "F.Mask" "F.Paste")
			(net "P3V3_AUX")
		)
		(pad "2" smd circle
			(at 0.40005 0)
			(size 0 0)
			(layers "F.Cu" "F.Mask" "F.Paste")
			(net "PWRGD_P3V3_AUX_PDB_BUF_R")
		)
	)
	(footprint ""
		(layer "F.Cu")
		(at 413.520382 -29.877258)
		(property "Reference" "R1335"
			(at 0 0 0)
			(layer "F.SilkS")
			(hide yes)
			(effects
				(font
					(size 1.27 1.27)
				)
			)
		)
		(property "Value" ""
			(at 0 0 0)
			(layer "F.Fab")
			(effects
				(font
					(size 1.27 1.27)
				)
			)
		)
		(duplicate_pad_numbers_are_jumpers no)
		(fp_line
			(start -0.7874 -0.4064)
			(end 0.7874 -0.4064)
			(stroke
				(width 0.1524)
				(type default)
			)
			(layer "F.SilkS")
		)
		(fp_line
			(start -0.7874 0.4064)
			(end -0.7874 -0.4064)
			(stroke
				(width 0.1524)
				(type default)
			)
			(layer "F.SilkS")
		)
		(fp_line
			(start 0.7874 -0.4064)
			(end 0.7874 0.4064)
			(stroke
				(width 0.1524)
				(type default)
			)
			(layer "F.SilkS")
		)
		(fp_line
			(start 0.7874 0.4064)
			(end -0.7874 0.4064)
			(stroke
				(width 0.1524)
				(type default)
			)
			(layer "F.SilkS")
		)
		(fp_line
			(start -0.67945 -0.305054)
			(end -0.12065 -0.305054)
			(stroke
				(width 0.1)
				(type default)
			)
			(layer "F.Fab")
		)
		(fp_line
			(start -0.67945 0.3048)
			(end -0.67945 -0.305054)
			(stroke
				(width 0.1)
				(type default)
			)
			(layer "F.Fab")
		)
		(fp_line
			(start -0.12065 -0.305054)
			(end -0.12065 -0.2794)
			(stroke
				(width 0.1)
				(type default)
			)
			(layer "F.Fab")
		)
		(fp_line
			(start -0.12065 -0.2794)
			(end 0.12065 -0.2794)
			(stroke
				(width 0.1)
				(type default)
			)
			(layer "F.Fab")
		)
		(fp_line
			(start -0.12065 0.2794)
			(end -0.12065 0.3048)
			(stroke
				(width 0.1)
				(type default)
			)
			(layer "F.Fab")
		)
		(fp_line
			(start -0.12065 0.3048)
			(end -0.67945 0.3048)
			(stroke
				(width 0.1)
				(type default)
			)
			(layer "F.Fab")
		)
		(fp_line
			(start 0.120396 0.2794)
			(end -0.12065 0.2794)
			(stroke
				(width 0.1)
				(type default)
			)
			(layer "F.Fab")
		)
		(fp_line
			(start 0.120396 0.3048)
			(end 0.120396 0.2794)
			(stroke
				(width 0.1)
				(type default)
			)
			(layer "F.Fab")
		)
		(fp_line
			(start 0.12065 -0.3048)
			(end 0.67945 -0.3048)
			(stroke
				(width 0.1)
				(type default)
			)
			(layer "F.Fab")
		)
		(fp_line
			(start 0.12065 -0.2794)
			(end 0.12065 -0.3048)
			(stroke
				(width 0.1)
				(type default)
			)
			(layer "F.Fab")
		)
		(fp_line
			(start 0.67945 -0.3048)
			(end 0.67945 0.3048)
			(stroke
				(width 0.1)
				(type default)
			)
			(layer "F.Fab")
		)
		(fp_line
			(start 0.67945 0.3048)
			(end 0.120396 0.3048)
			(stroke
				(width 0.1)
				(type default)
			)
			(layer "F.Fab")
		)
		(pad "1" smd circle
			(at -0.40005 0)
			(size 0 0)
			(layers "F.Cu" "F.Mask" "F.Paste")
			(net "GND")
		)
		(pad "2" smd circle
			(at 0.40005 0)
			(size 0 0)
			(layers "F.Cu" "F.Mask" "F.Paste")
			(net "PD_PASSWORD_CLEAR")
		)
	)
	(footprint ""
		(layer "F.Cu")
		(at 90.839798 -402.371052 -90)
		(property "Reference" "C738"
			(at 0 0 270)
			(layer "F.SilkS")
			(hide yes)
			(effects
				(font
					(size 1.27 1.27)
				)
			)
		)
		(property "Value" ""
			(at 0 0 270)
			(layer "F.Fab")
			(effects
				(font
					(size 1.27 1.27)
				)
			)
		)
		(duplicate_pad_numbers_are_jumpers no)
		(fp_line
			(start -0.299974 0.150114)
			(end -0.299974 -0.150114)
			(stroke
				(width 0.1)
				(type default)
			)
			(layer "F.Fab")
		)
		(fp_line
			(start 0.299974 0.150114)
			(end -0.299974 0.150114)
			(stroke
				(width 0.1)
				(type default)
			)
			(layer "F.Fab")
		)
		(fp_line
			(start -0.299974 -0.150114)
			(end 0.299974 -0.150114)
			(stroke
				(width 0.1)
				(type default)
			)
			(layer "F.Fab")
		)
		(fp_line
			(start 0.299974 -0.150114)
			(end 0.299974 0.150114)
			(stroke
				(width 0.1)
				(type default)
			)
			(layer "F.Fab")
		)
		(pad "1" smd rect
			(at -0.2667 0 270)
			(size 0.3048 0.381)
			(layers "F.Cu" "F.Mask" "F.Paste")
			(net "P5E_CPU1_PE0_TX_C_DN<1>")
		)
		(pad "2" smd rect
			(at 0.2667 0 270)
			(size 0.3048 0.381)
			(layers "F.Cu" "F.Mask" "F.Paste")
			(net "P5E_CPU1_PE0_TX_DN<1>")
		)
	)
	(footprint ""
		(layer "F.Cu")
		(at 17.045432 -107.123484)
		(property "Reference" "R4483"
			(at 0 0 0)
			(layer "F.SilkS")
			(hide yes)
			(effects
				(font
					(size 1.27 1.27)
				)
			)
		)
		(property "Value" ""
			(at 0 0 0)
			(layer "F.Fab")
			(effects
				(font
					(size 1.27 1.27)
				)
			)
		)
		(duplicate_pad_numbers_are_jumpers no)
		(fp_line
			(start 0.015748 -0.4064)
			(end 0.7874 -0.4064)
			(stroke
				(width 0.1524)
				(type default)
			)
			(layer "F.SilkS")
		)
		(fp_line
			(start 0.7874 -0.4064)
			(end 0.7874 0.4064)
			(stroke
				(width 0.1524)
				(type default)
			)
			(layer "F.SilkS")
		)
		(fp_line
			(start 0.7874 0.4064)
			(end 0.028448 0.4064)
			(stroke
				(width 0.1524)
				(type default)
			)
			(layer "F.SilkS")
		)
		(fp_line
			(start -0.67945 -0.305054)
			(end -0.12065 -0.305054)
			(stroke
				(width 0.1)
				(type default)
			)
			(layer "F.Fab")
		)
		(fp_line
			(start -0.67945 0.3048)
			(end -0.67945 -0.305054)
			(stroke
				(width 0.1)
				(type default)
			)
			(layer "F.Fab")
		)
		(fp_line
			(start -0.12065 -0.305054)
			(end -0.12065 -0.2794)
			(stroke
				(width 0.1)
				(type default)
			)
			(layer "F.Fab")
		)
		(fp_line
			(start -0.12065 -0.2794)
			(end 0.12065 -0.2794)
			(stroke
				(width 0.1)
				(type default)
			)
			(layer "F.Fab")
		)
		(fp_line
			(start -0.12065 0.2794)
			(end -0.12065 0.3048)
			(stroke
				(width 0.1)
				(type default)
			)
			(layer "F.Fab")
		)
		(fp_line
			(start -0.12065 0.3048)
			(end -0.67945 0.3048)
			(stroke
				(width 0.1)
				(type default)
			)
			(layer "F.Fab")
		)
		(fp_line
			(start 0.120396 0.2794)
			(end -0.12065 0.2794)
			(stroke
				(width 0.1)
				(type default)
			)
			(layer "F.Fab")
		)
		(fp_line
			(start 0.120396 0.3048)
			(end 0.120396 0.2794)
			(stroke
				(width 0.1)
				(type default)
			)
			(layer "F.Fab")
		)
		(fp_line
			(start 0.12065 -0.3048)
			(end 0.67945 -0.3048)
			(stroke
				(width 0.1)
				(type default)
			)
			(layer "F.Fab")
		)
		(fp_line
			(start 0.12065 -0.2794)
			(end 0.12065 -0.3048)
			(stroke
				(width 0.1)
				(type default)
			)
			(layer "F.Fab")
		)
		(fp_line
			(start 0.67945 -0.3048)
			(end 0.67945 0.3048)
			(stroke
				(width 0.1)
				(type default)
			)
			(layer "F.Fab")
		)
		(fp_line
			(start 0.67945 0.3048)
			(end 0.120396 0.3048)
			(stroke
				(width 0.1)
				(type default)
			)
			(layer "F.Fab")
		)
		(pad "1" smd circle
			(at -0.40005 0)
			(size 0 0)
			(layers "F.Cu" "F.Mask" "F.Paste")
			(net "USB2_HOST_BMC_B_BUF_DN")
		)
		(pad "2" smd circle
			(at 0.40005 0)
			(size 0 0)
			(layers "F.Cu" "F.Mask" "F.Paste")
			(net "GND")
		)
	)
	(footprint ""
		(layer "F.Cu")
		(at 63.30188 -16.220948 -90)
		(property "Reference" "R3169"
			(at 0 0 270)
			(layer "F.SilkS")
			(hide yes)
			(effects
				(font
					(size 1.27 1.27)
				)
			)
		)
		(property "Value" ""
			(at 0 0 270)
			(layer "F.Fab")
			(effects
				(font
					(size 1.27 1.27)
				)
			)
		)
		(duplicate_pad_numbers_are_jumpers no)
		(fp_line
			(start -0.7874 0.4064)
			(end -0.7874 -0.4064)
			(stroke
				(width 0.1524)
				(type default)
			)
			(layer "F.SilkS")
		)
		(fp_line
			(start 0.7874 0.4064)
			(end -0.7874 0.4064)
			(stroke
				(width 0.1524)
				(type default)
			)
			(layer "F.SilkS")
		)
		(fp_line
			(start -0.7874 -0.4064)
			(end 0.7874 -0.4064)
			(stroke
				(width 0.1524)
				(type default)
			)
			(layer "F.SilkS")
		)
		(fp_line
			(start 0.7874 -0.4064)
			(end 0.7874 0.4064)
			(stroke
				(width 0.1524)
				(type default)
			)
			(layer "F.SilkS")
		)
		(fp_line
			(start -0.67945 0.3048)
			(end -0.67945 -0.305054)
			(stroke
				(width 0.1)
				(type default)
			)
			(layer "F.Fab")
		)
		(fp_line
			(start -0.12065 0.3048)
			(end -0.67945 0.3048)
			(stroke
				(width 0.1)
				(type default)
			)
			(layer "F.Fab")
		)
		(fp_line
			(start 0.120396 0.3048)
			(end 0.120396 0.2794)
			(stroke
				(width 0.1)
				(type default)
			)
			(layer "F.Fab")
		)
		(fp_line
			(start 0.67945 0.3048)
			(end 0.120396 0.3048)
			(stroke
				(width 0.1)
				(type default)
			)
			(layer "F.Fab")
		)
		(fp_line
			(start -0.12065 0.2794)
			(end -0.12065 0.3048)
			(stroke
				(width 0.1)
				(type default)
			)
			(layer "F.Fab")
		)
		(fp_line
			(start 0.120396 0.2794)
			(end -0.12065 0.2794)
			(stroke
				(width 0.1)
				(type default)
			)
			(layer "F.Fab")
		)
		(fp_line
			(start -0.12065 -0.2794)
			(end 0.12065 -0.2794)
			(stroke
				(width 0.1)
				(type default)
			)
			(layer "F.Fab")
		)
		(fp_line
			(start 0.12065 -0.2794)
			(end 0.12065 -0.3048)
			(stroke
				(width 0.1)
				(type default)
			)
			(layer "F.Fab")
		)
		(fp_line
			(start 0.12065 -0.3048)
			(end 0.67945 -0.3048)
			(stroke
				(width 0.1)
				(type default)
			)
			(layer "F.Fab")
		)
		(fp_line
			(start 0.67945 -0.3048)
			(end 0.67945 0.3048)
			(stroke
				(width 0.1)
				(type default)
			)
			(layer "F.Fab")
		)
		(fp_line
			(start -0.67945 -0.305054)
			(end -0.12065 -0.305054)
			(stroke
				(width 0.1)
				(type default)
			)
			(layer "F.Fab")
		)
		(fp_line
			(start -0.12065 -0.305054)
			(end -0.12065 -0.2794)
			(stroke
				(width 0.1)
				(type default)
			)
			(layer "F.Fab")
		)
		(pad "1" smd circle
			(at -0.40005 0 270)
			(size 0 0)
			(layers "F.Cu" "F.Mask" "F.Paste")
			(net "OCP_V3_2_ISO_BIF0_EN")
		)
		(pad "2" smd circle
			(at 0.40005 0 270)
			(size 0 0)
			(layers "F.Cu" "F.Mask" "F.Paste")
			(net "OCP_V3_2_BIF0_R_N")
		)
	)
	(footprint ""
		(layer "F.Cu")
		(at 181.80812 -411.20822 -90)
		(property "Reference" "C2388"
			(at 0 0 270)
			(layer "F.SilkS")
			(hide yes)
			(effects
				(font
					(size 1.27 1.27)
				)
			)
		)
		(property "Value" ""
			(at 0 0 270)
			(layer "F.Fab")
			(effects
				(font
					(size 1.27 1.27)
				)
			)
		)
		(duplicate_pad_numbers_are_jumpers no)
		(fp_line
			(start -0.7874 0.4064)
			(end -0.7874 -0.4064)
			(stroke
				(width 0.1524)
				(type default)
			)
			(layer "F.SilkS")
		)
		(fp_line
			(start 0.7874 0.4064)
			(end -0.7874 0.4064)
			(stroke
				(width 0.1524)
				(type default)
			)
			(layer "F.SilkS")
		)
		(fp_line
			(start -0.7874 -0.4064)
			(end 0.7874 -0.4064)
			(stroke
				(width 0.1524)
				(type default)
			)
			(layer "F.SilkS")
		)
		(fp_line
			(start 0.7874 -0.4064)
			(end 0.7874 0.4064)
			(stroke
				(width 0.1524)
				(type default)
			)
			(layer "F.SilkS")
		)
		(fp_line
			(start -0.67945 0.3048)
			(end -0.67945 -0.305054)
			(stroke
				(width 0.1)
				(type default)
			)
			(layer "F.Fab")
		)
		(fp_line
			(start -0.12065 0.3048)
			(end -0.67945 0.3048)
			(stroke
				(width 0.1)
				(type default)
			)
			(layer "F.Fab")
		)
		(fp_line
			(start 0.120396 0.3048)
			(end 0.120396 0.2794)
			(stroke
				(width 0.1)
				(type default)
			)
			(layer "F.Fab")
		)
		(fp_line
			(start 0.67945 0.3048)
			(end 0.120396 0.3048)
			(stroke
				(width 0.1)
				(type default)
			)
			(layer "F.Fab")
		)
		(fp_line
			(start -0.12065 0.2794)
			(end -0.12065 0.3048)
			(stroke
				(width 0.1)
				(type default)
			)
			(layer "F.Fab")
		)
		(fp_line
			(start 0.120396 0.2794)
			(end -0.12065 0.2794)
			(stroke
				(width 0.1)
				(type default)
			)
			(layer "F.Fab")
		)
		(fp_line
			(start -0.12065 -0.2794)
			(end 0.12065 -0.2794)
			(stroke
				(width 0.1)
				(type default)
			)
			(layer "F.Fab")
		)
		(fp_line
			(start 0.12065 -0.2794)
			(end 0.12065 -0.3048)
			(stroke
				(width 0.1)
				(type default)
			)
			(layer "F.Fab")
		)
		(fp_line
			(start 0.12065 -0.3048)
			(end 0.67945 -0.3048)
			(stroke
				(width 0.1)
				(type default)
			)
			(layer "F.Fab")
		)
		(fp_line
			(start 0.67945 -0.3048)
			(end 0.67945 0.3048)
			(stroke
				(width 0.1)
				(type default)
			)
			(layer "F.Fab")
		)
		(fp_line
			(start -0.67945 -0.305054)
			(end -0.12065 -0.305054)
			(stroke
				(width 0.1)
				(type default)
			)
			(layer "F.Fab")
		)
		(fp_line
			(start -0.12065 -0.305054)
			(end -0.12065 -0.2794)
			(stroke
				(width 0.1)
				(type default)
			)
			(layer "F.Fab")
		)
		(pad "1" smd circle
			(at -0.40005 0 270)
			(size 0 0)
			(layers "F.Cu" "F.Mask" "F.Paste")
			(net "OC_P2V5_COMP")
		)
		(pad "2" smd circle
			(at 0.40005 0 270)
			(size 0 0)
			(layers "F.Cu" "F.Mask" "F.Paste")
			(net "GND")
		)
	)
	(footprint ""
		(layer "F.Cu")
		(at 183.45658 -414.76422 90)
		(property "Reference" "U344"
			(at -0.2413 -3.16611 90)
			(unlocked yes)
			(layer "F.SilkS")
			(effects
				(font
					(size 0.7874 0.5842)
					(thickness 0.1524)
				)
			)
		)
		(property "Value" ""
			(at 0 0 90)
			(layer "F.Fab")
			(effects
				(font
					(size 1.27 1.27)
				)
			)
		)
		(duplicate_pad_numbers_are_jumpers no)
		(fp_line
			(start 2.032 -1.549908)
			(end 2.032 1.549908)
			(stroke
				(width 0.1524)
				(type default)
			)
			(layer "F.SilkS")
		)
		(fp_line
			(start 0.508 -1.549908)
			(end 2.032 -1.549908)
			(stroke
				(width 0.1524)
				(type default)
			)
			(layer "F.SilkS")
		)
		(fp_line
			(start -0.508 -1.549908)
			(end 0 -0.762)
			(stroke
				(width 0.1524)
				(type default)
			)
			(layer "F.SilkS")
		)
		(fp_line
			(start -2.032 -1.549908)
			(end -0.508 -1.549908)
			(stroke
				(width 0.1524)
				(type default)
			)
			(layer "F.SilkS")
		)
		(fp_line
			(start 0 -0.762)
			(end 0.508 -1.549908)
			(stroke
				(width 0.1524)
				(type default)
			)
			(layer "F.SilkS")
		)
		(fp_line
			(start 2.032 1.549908)
			(end -2.032 1.549908)
			(stroke
				(width 0.1524)
				(type default)
			)
			(layer "F.SilkS")
		)
		(fp_line
			(start -2.032 1.549908)
			(end -2.032 -1.549908)
			(stroke
				(width 0.1524)
				(type default)
			)
			(layer "F.SilkS")
		)
		(fp_poly
			(pts
				(xy -1.390396 -2.629408) (xy -2.406396 -2.629154) (xy -1.898396 -1.613408)
			)
			(stroke
				(width 0)
				(type default)
			)
			(fill yes)
			(layer "F.SilkS")
		)
		(fp_line
			(start 0.849884 -1.549908)
			(end 0.849884 1.549908)
			(stroke
				(width 0.1)
				(type default)
			)
			(layer "F.Fab")
		)
		(fp_line
			(start -0.849884 -1.549908)
			(end 0.849884 -1.549908)
			(stroke
				(width 0.1)
				(type default)
			)
			(layer "F.Fab")
		)
		(fp_line
			(start 0.849884 1.549908)
			(end -0.849884 1.549908)
			(stroke
				(width 0.1)
				(type default)
			)
			(layer "F.Fab")
		)
		(fp_line
			(start -0.849884 1.549908)
			(end -0.849884 -1.549908)
			(stroke
				(width 0.1)
				(type default)
			)
			(layer "F.Fab")
		)
		(fp_poly
			(pts
				(xy -3.2004 -1.45796) (xy -3.2004 -0.44196) (xy -2.1844 -0.94996)
			)
			(stroke
				(width 0)
				(type default)
			)
			(fill yes)
			(layer "F.Fab")
		)
		(pad "1" smd rect
			(at -1.35001 -0.94996)
			(size 0.6096 1.0668)
			(layers "F.Cu" "F.Mask" "F.Paste")
			(net "OC_P2V5_COMP")
		)
		(pad "2" smd rect
			(at -1.35001 0)
			(size 0.6096 1.0668)
			(layers "F.Cu" "F.Mask" "F.Paste")
			(net "GND")
		)
		(pad "3" smd rect
			(at -1.35001 0.94996)
			(size 0.6096 1.0668)
			(layers "F.Cu" "F.Mask" "F.Paste")
			(net "HSC_OC_VOL")
		)
		(pad "4" smd rect
			(at 1.35001 0.94996)
			(size 0.6096 1.0668)
			(layers "F.Cu" "F.Mask" "F.Paste")
			(net "HSC_D_OC_R2")
		)
		(pad "5" smd rect
			(at 1.35001 -0.94996)
			(size 0.6096 1.0668)
			(layers "F.Cu" "F.Mask" "F.Paste")
			(net "P12V_AUX")
		)
	)
)
